# T6G (Grand Teton) — schematic netlist excerpt (pin names and nets, part order shuffled) for the footprints in the layout excerpt that follows; sources: Cadence DE-HDL packaged netlist, KiCad conversion of 04192023_DAF0TMB3IC0_F0TG_MB_C_brd_V02_OCP.brd

PC583_1  Q_CAP  0.1UF 25V 10% X7R  pkg 0402  page 198 : A = SW_P12V_AUX_PVDDCR_SOC_P0_FLT ; B = GND

JP10  CONN3_210HP1030BR1  CONN3_210-HP1-030BR1 IO  pkg HEADER1X3XG  page 268
  \1\  = SMB_SML1_PMBUS_HSC_R1_SCL
  \2\  = SMB_SML1_PMBUS_HSC_R1_SDA
  \3\  = GND

(kicad_pcb
	(version 20260206)
	(generator "pcbnew")
	(generator_version "10.0")
	(general
		(thickness 1.6)
		(legacy_teardrops no)
	)
	(paper "A4")
	(title_block
		(title "04192023_DAF0TMB3IC0_F0TG_MB_C_brd_V02_OCP.brd")
		(comment 1 "Grand Teton / footprints 293-294 of 8354")
	)
	(layers
		(0 "F.Cu" signal "TOP")
		(4 "In1.Cu" signal "GND")
		(6 "In2.Cu" signal "IN1")
		(8 "In3.Cu" signal "GND1")
		(10 "In4.Cu" signal "IN2")
		(12 "In5.Cu" signal "GND2")
		(14 "In6.Cu" signal "IN3")
		(16 "In7.Cu" signal "GND3")
		(18 "In8.Cu" signal "VCC")
		(20 "In9.Cu" signal "VCC1")
		(22 "In10.Cu" signal "GND4")
		(24 "In11.Cu" signal "IN4")
		(26 "In12.Cu" signal "GND5")
		(28 "In13.Cu" signal "IN5")
		(30 "In14.Cu" signal "GND6")
		(32 "In15.Cu" signal "IN6")
		(34 "In16.Cu" signal "GND7")
		(2 "B.Cu" signal "BOTTOM")
		(9 "F.Adhes" user "F.Adhesive")
		(11 "B.Adhes" user "B.Adhesive")
		(13 "F.Paste" user "Package Geometry/Pastemask Top")
		(15 "B.Paste" user "Package Geometry/Pastemask Bottom")
		(5 "F.SilkS" user "Ref Des/Silkscreen Top")
		(7 "B.SilkS" user "Ref Des/Silkscreen Bottom")
		(1 "F.Mask" user "Board Geometry/Soldermask Top")
		(3 "B.Mask" user "Board Geometry/Soldermask Bottom")
		(17 "Dwgs.User" user "User.Drawings")
		(19 "Cmts.User" user "User.Comments")
		(21 "Eco1.User" user "User.Eco1")
		(23 "Eco2.User" user "User.Eco2")
		(25 "Edge.Cuts" user "Board Geometry/Outline")
		(27 "Margin" user)
		(31 "F.CrtYd" user "Package Geometry/Place Bound Top")
		(29 "B.CrtYd" user "Package Geometry/Place Bound Bottom")
		(35 "F.Fab" user "Ref Des/Assembly Top")
		(33 "B.Fab" user "Ref Des/Assembly Bottom")
	)
	(footprint ""
		(layer "F.Cu")
		(at 192.324736 -437.584088)
		(property "Reference" "JP10"
			(at -1.4097 -2.009648 0)
			(unlocked yes)
			(layer "F.SilkS")
			(effects
				(font
					(size 0.7874 0.5842)
					(thickness 0.1524)
				)
				(justify left)
			)
		)
		(property "Value" ""
			(at 0 0 0)
			(layer "F.Fab")
			(effects
				(font
					(size 1.27 1.27)
				)
			)
		)
		(duplicate_pad_numbers_are_jumpers no)
		(fp_line
			(start -1.249934 -1.320038)
			(end 1.249934 -1.320038)
			(stroke
				(width 0.1524)
				(type default)
			)
			(layer "F.SilkS")
		)
		(fp_line
			(start -1.249934 6.400038)
			(end -1.249934 -1.320038)
			(stroke
				(width 0.1524)
				(type default)
			)
			(layer "F.SilkS")
		)
		(fp_line
			(start 1.249934 -1.320038)
			(end 1.249934 6.400038)
			(stroke
				(width 0.1524)
				(type default)
			)
			(layer "F.SilkS")
		)
		(fp_line
			(start 1.249934 6.400038)
			(end -1.249934 6.400038)
			(stroke
				(width 0.1524)
				(type default)
			)
			(layer "F.SilkS")
		)
		(fp_poly
			(pts
				(xy -2.5654 0.556514) (xy -2.5654 -0.556514) (xy -1.452372 0)
			)
			(stroke
				(width 0)
				(type default)
			)
			(fill yes)
			(layer "F.SilkS")
		)
		(fp_line
			(start -1.249934 -1.320038)
			(end 1.249934 -1.320038)
			(stroke
				(width 0.1)
				(type default)
			)
			(layer "F.Fab")
		)
		(fp_line
			(start -1.249934 6.400038)
			(end -1.249934 -1.320038)
			(stroke
				(width 0.1)
				(type default)
			)
			(layer "F.Fab")
		)
		(fp_line
			(start 1.249934 -1.320038)
			(end 1.249934 6.400038)
			(stroke
				(width 0.1)
				(type default)
			)
			(layer "F.Fab")
		)
		(fp_line
			(start 1.249934 6.400038)
			(end -1.249934 6.400038)
			(stroke
				(width 0.1)
				(type default)
			)
			(layer "F.Fab")
		)
		(fp_poly
			(pts
				(xy -2.5654 -0.556514) (xy -1.452372 0) (xy -2.5654 0.556514)
			)
			(stroke
				(width 0)
				(type default)
			)
			(fill yes)
			(layer "F.Fab")
		)
		(fp_text user "3"
			(at -1.778 5.13207 0)
			(unlocked yes)
			(layer "F.SilkS")
			(effects
				(font
					(size 0.7874 0.5842)
					(thickness 0.1524)
				)
			)
		)
		(fp_text user "1"
			(at -1.477264 0.136398 0)
			(unlocked yes)
			(layer "B.SilkS")
			(effects
				(font
					(size 0.7874 0.5842)
					(thickness 0.1524)
				)
				(justify mirror)
			)
		)
		(fp_text user "3"
			(at -1.411732 5.289296 0)
			(unlocked yes)
			(layer "B.SilkS")
			(effects
				(font
					(size 0.7874 0.5842)
					(thickness 0.1524)
				)
				(justify mirror)
			)
		)
		(fp_text user "3"
			(at -1.1557 5.18287 0)
			(unlocked yes)
			(layer "B.Fab")
			(effects
				(font
					(size 0.7874 0.5842)
					(thickness 0.1524)
				)
				(justify mirror)
			)
		)
		(fp_text user "1"
			(at -1.143 0.02667 0)
			(unlocked yes)
			(layer "B.Fab")
			(effects
				(font
					(size 0.7874 0.5842)
					(thickness 0.1524)
				)
				(justify mirror)
			)
		)
		(fp_text user "3"
			(at -1.778 5.13207 0)
			(unlocked yes)
			(layer "F.Fab")
			(effects
				(font
					(size 0.7874 0.5842)
					(thickness 0.1524)
				)
			)
		)
		(pad "1" thru_hole rect
			(at 0 0)
			(size 1.5494 1.5494)
			(drill 1.0414)
			(layers "*.Cu" "*.Mask")
			(remove_unused_layers no)
			(net "SMB_SML1_PMBUS_HSC_R1_SCL")
			(clearance 0)
			(padstack
				(mode front_inner_back)
				(layer "Inner"
					(shape circle)
					(size 1.5494 1.5494)
					(clearance 0)
				)
				(layer "B.Cu"
					(shape rect)
					(size 1.5494 1.5494)
					(clearance 0)
				)
			)
		)
		(pad "2" thru_hole circle
			(at 0 2.54)
			(size 1.5494 1.5494)
			(drill 1.0414)
			(layers "*.Cu" "*.Mask")
			(remove_unused_layers no)
			(net "SMB_SML1_PMBUS_HSC_R1_SDA")
			(clearance 0)
		)
		(pad "3" thru_hole circle
			(at 0 5.08)
			(size 1.5494 1.5494)
			(drill 1.0414)
			(layers "*.Cu" "*.Mask")
			(remove_unused_layers no)
			(net "GND")
			(clearance 0)
		)
	)
	(footprint ""
		(layer "F.Cu")
		(at 393.148058 -177.04562 90)
		(property "Reference" "PC583_1"
			(at 0 0 90)
			(layer "F.SilkS")
			(hide yes)
			(effects
				(font
					(size 1.27 1.27)
				)
			)
		)
		(property "Value" ""
			(at 0 0 90)
			(layer "F.Fab")
			(effects
				(font
					(size 1.27 1.27)
				)
			)
		)
		(duplicate_pad_numbers_are_jumpers no)
		(fp_line
			(start 0.7874 -0.4064)
			(end 0.7874 0.4064)
			(stroke
				(width 0.1524)
				(type default)
			)
			(layer "F.SilkS")
		)
		(fp_line
			(start -0.7874 -0.4064)
			(end 0.7874 -0.4064)
			(stroke
				(width 0.1524)
				(type default)
			)
			(layer "F.SilkS")
		)
		(fp_line
			(start 0.7874 0.4064)
			(end -0.7874 0.4064)
			(stroke
				(width 0.1524)
				(type default)
			)
			(layer "F.SilkS")
		)
		(fp_line
			(start -0.7874 0.4064)
			(end -0.7874 -0.4064)
			(stroke
				(width 0.1524)
				(type default)
			)
			(layer "F.SilkS")
		)
		(fp_line
			(start -0.12065 -0.305054)
			(end -0.12065 -0.2794)
			(stroke
				(width 0.1)
				(type default)
			)
			(layer "F.Fab")
		)
		(fp_line
			(start -0.67945 -0.305054)
			(end -0.12065 -0.305054)
			(stroke
				(width 0.1)
				(type default)
			)
			(layer "F.Fab")
		)
		(fp_line
			(start 0.67945 -0.3048)
			(end 0.67945 0.3048)
			(stroke
				(width 0.1)
				(type default)
			)
			(layer "F.Fab")
		)
		(fp_line
			(start 0.12065 -0.3048)
			(end 0.67945 -0.3048)
			(stroke
				(width 0.1)
				(type default)
			)
			(layer "F.Fab")
		)
		(fp_line
			(start 0.12065 -0.2794)
			(end 0.12065 -0.3048)
			(stroke
				(width 0.1)
				(type default)
			)
			(layer "F.Fab")
		)
		(fp_line
			(start -0.12065 -0.2794)
			(end 0.12065 -0.2794)
			(stroke
				(width 0.1)
				(type default)
			)
			(layer "F.Fab")
		)
		(fp_line
			(start 0.120396 0.2794)
			(end -0.12065 0.2794)
			(stroke
				(width 0.1)
				(type default)
			)
			(layer "F.Fab")
		)
		(fp_line
			(start -0.12065 0.2794)
			(end -0.12065 0.3048)
			(stroke
				(width 0.1)
				(type default)
			)
			(layer "F.Fab")
		)
		(fp_line
			(start 0.67945 0.3048)
			(end 0.120396 0.3048)
			(stroke
				(width 0.1)
				(type default)
			)
			(layer "F.Fab")
		)
		(fp_line
			(start 0.120396 0.3048)
			(end 0.120396 0.2794)
			(stroke
				(width 0.1)
				(type default)
			)
			(layer "F.Fab")
		)
		(fp_line
			(start -0.12065 0.3048)
			(end -0.67945 0.3048)
			(stroke
				(width 0.1)
				(type default)
			)
			(layer "F.Fab")
		)
		(fp_line
			(start -0.67945 0.3048)
			(end -0.67945 -0.305054)
			(stroke
				(width 0.1)
				(type default)
			)
			(layer "F.Fab")
		)
		(pad "1" smd circle
			(at -0.40005 0 90)
			(size 0 0)
			(layers "F.Cu" "F.Mask" "F.Paste")
			(net "SW_P12V_AUX_PVDDCR_SOC_P0_FLT")
		)
		(pad "2" smd circle
			(at 0.40005 0 90)
			(size 0 0)
			(layers "F.Cu" "F.Mask" "F.Paste")
			(net "GND")
		)
	)
)
